(kicad_pcb
	(version 20260206)
	(generator "pcbnew")
	(generator_version "10.0")
	(general
		(thickness 1.6)
		(legacy_teardrops no)
	)
	(paper "A4")
	(title_block
		(title "04192023_DAF0TMB3IC0_F0TG_MB_C_brd_V02_OCP.brd")
		(comment 1 "Grand Teton / footprints 5459-5464 of 8354")
	)
	(layers
		(0 "F.Cu" signal "TOP")
		(4 "In1.Cu" signal "GND")
		(6 "In2.Cu" signal "IN1")
		(8 "In3.Cu" signal "GND1")
		(10 "In4.Cu" signal "IN2")
		(12 "In5.Cu" signal "GND2")
		(14 "In6.Cu" signal "IN3")
		(16 "In7.Cu" signal "GND3")
		(18 "In8.Cu" signal "VCC")
		(20 "In9.Cu" signal "VCC1")
		(22 "In10.Cu" signal "GND4")
		(24 "In11.Cu" signal "IN4")
		(26 "In12.Cu" signal "GND5")
		(28 "In13.Cu" signal "IN5")
		(30 "In14.Cu" signal "GND6")
		(32 "In15.Cu" signal "IN6")
		(34 "In16.Cu" signal "GND7")
		(2 "B.Cu" signal "BOTTOM")
		(9 "F.Adhes" user "F.Adhesive")
		(11 "B.Adhes" user "B.Adhesive")
		(13 "F.Paste" user "Package Geometry/Pastemask Top")
		(15 "B.Paste" user "Package Geometry/Pastemask Bottom")
		(5 "F.SilkS" user "Ref Des/Silkscreen Top")
		(7 "B.SilkS" user "Ref Des/Silkscreen Bottom")
		(1 "F.Mask" user "Board Geometry/Soldermask Top")
		(3 "B.Mask" user "Board Geometry/Soldermask Bottom")
		(17 "Dwgs.User" user "User.Drawings")
		(19 "Cmts.User" user "User.Comments")
		(21 "Eco1.User" user "User.Eco1")
		(23 "Eco2.User" user "User.Eco2")
		(25 "Edge.Cuts" user "Board Geometry/Outline")
		(27 "Margin" user)
		(31 "F.CrtYd" user "Package Geometry/Place Bound Top")
		(29 "B.CrtYd" user "Package Geometry/Place Bound Bottom")
		(35 "F.Fab" user "Ref Des/Assembly Top")
		(33 "B.Fab" user "Ref Des/Assembly Bottom")
	)
	(footprint ""
		(layer "B.Cu")
		(at 364.312454 -268.41831)
		(property "Reference" "C2219"
			(at 0 0 0)
			(layer "B.SilkS")
			(hide yes)
			(effects
				(font
					(size 1.27 1.27)
				)
				(justify mirror)
			)
		)
		(property "Value" ""
			(at 0 0 0)
			(layer "B.Fab")
			(effects
				(font
					(size 1.27 1.27)
				)
				(justify mirror)
			)
		)
		(duplicate_pad_numbers_are_jumpers no)
		(fp_line
			(start -0.7874 -0.4064)
			(end -0.7874 0.4064)
			(stroke
				(width 0.1524)
				(type default)
			)
			(layer "B.SilkS")
		)
		(fp_line
			(start -0.7874 0.4064)
			(end 0.7874 0.4064)
			(stroke
				(width 0.1524)
				(type default)
			)
			(layer "B.SilkS")
		)
		(fp_line
			(start 0.7874 -0.4064)
			(end -0.7874 -0.4064)
			(stroke
				(width 0.1524)
				(type default)
			)
			(layer "B.SilkS")
		)
		(fp_line
			(start 0.7874 0.4064)
			(end 0.7874 -0.4064)
			(stroke
				(width 0.1524)
				(type default)
			)
			(layer "B.SilkS")
		)
		(fp_line
			(start -0.67945 -0.3048)
			(end -0.67945 0.3048)
			(stroke
				(width 0.1)
				(type default)
			)
			(layer "B.Fab")
		)
		(fp_line
			(start -0.67945 0.3048)
			(end -0.120396 0.3048)
			(stroke
				(width 0.1)
				(type default)
			)
			(layer "B.Fab")
		)
		(fp_line
			(start -0.12065 -0.3048)
			(end -0.67945 -0.3048)
			(stroke
				(width 0.1)
				(type default)
			)
			(layer "B.Fab")
		)
		(fp_line
			(start -0.12065 -0.2794)
			(end -0.12065 -0.3048)
			(stroke
				(width 0.1)
				(type default)
			)
			(layer "B.Fab")
		)
		(fp_line
			(start -0.120396 0.2794)
			(end 0.12065 0.2794)
			(stroke
				(width 0.1)
				(type default)
			)
			(layer "B.Fab")
		)
		(fp_line
			(start -0.120396 0.3048)
			(end -0.120396 0.2794)
			(stroke
				(width 0.1)
				(type default)
			)
			(layer "B.Fab")
		)
		(fp_line
			(start 0.12065 -0.305054)
			(end 0.12065 -0.2794)
			(stroke
				(width 0.1)
				(type default)
			)
			(layer "B.Fab")
		)
		(fp_line
			(start 0.12065 -0.2794)
			(end -0.12065 -0.2794)
			(stroke
				(width 0.1)
				(type default)
			)
			(layer "B.Fab")
		)
		(fp_line
			(start 0.12065 0.2794)
			(end 0.12065 0.3048)
			(stroke
				(width 0.1)
				(type default)
			)
			(layer "B.Fab")
		)
		(fp_line
			(start 0.12065 0.3048)
			(end 0.67945 0.3048)
			(stroke
				(width 0.1)
				(type default)
			)
			(layer "B.Fab")
		)
		(fp_line
			(start 0.67945 -0.305054)
			(end 0.12065 -0.305054)
			(stroke
				(width 0.1)
				(type default)
			)
			(layer "B.Fab")
		)
		(fp_line
			(start 0.67945 0.3048)
			(end 0.67945 -0.305054)
			(stroke
				(width 0.1)
				(type default)
			)
			(layer "B.Fab")
		)
		(pad "1" smd circle
			(at 0.40005 0 180)
			(size 0 0)
			(layers "B.Cu" "B.Mask" "B.Paste")
			(net "PVDDCR_CPU1_P0")
		)
		(pad "2" smd circle
			(at -0.40005 0 180)
			(size 0 0)
			(layers "B.Cu" "B.Mask" "B.Paste")
			(net "GND")
		)
	)
	(footprint ""
		(layer "B.Cu")
		(at 395.562582 -398.055084 90)
		(property "Reference" "C801"
			(at 0 0 90)
			(layer "B.SilkS")
			(hide yes)
			(effects
				(font
					(size 1.27 1.27)
				)
				(justify mirror)
			)
		)
		(property "Value" ""
			(at 0 0 90)
			(layer "B.Fab")
			(effects
				(font
					(size 1.27 1.27)
				)
				(justify mirror)
			)
		)
		(duplicate_pad_numbers_are_jumpers no)
		(fp_line
			(start 1.524 -0.762)
			(end -1.524 -0.762)
			(stroke
				(width 0.1524)
				(type default)
			)
			(layer "B.SilkS")
		)
		(fp_line
			(start -1.524 -0.762)
			(end -1.524 0.762)
			(stroke
				(width 0.1524)
				(type default)
			)
			(layer "B.SilkS")
		)
		(fp_line
			(start 1.524 0.762)
			(end 1.524 -0.762)
			(stroke
				(width 0.1524)
				(type default)
			)
			(layer "B.SilkS")
		)
		(fp_line
			(start -1.524 0.762)
			(end 1.524 0.762)
			(stroke
				(width 0.1524)
				(type default)
			)
			(layer "B.SilkS")
		)
		(fp_line
			(start 1.1049 -0.724916)
			(end 1.1049 0.724916)
			(stroke
				(width 0.1)
				(type default)
			)
			(layer "B.Fab")
		)
		(fp_line
			(start -1.1049 -0.724916)
			(end 1.1049 -0.724916)
			(stroke
				(width 0.1)
				(type default)
			)
			(layer "B.Fab")
		)
		(fp_line
			(start 1.1049 0.724916)
			(end -1.1049 0.724916)
			(stroke
				(width 0.1)
				(type default)
			)
			(layer "B.Fab")
		)
		(fp_line
			(start -1.1049 0.724916)
			(end -1.1049 -0.724916)
			(stroke
				(width 0.1)
				(type default)
			)
			(layer "B.Fab")
		)
		(pad "1" smd rect
			(at 0.889 0 90)
			(size 1.016 1.27)
			(layers "B.Cu" "B.Mask" "B.Paste")
			(net "P0V9_CPU0_RT_2D")
		)
		(pad "2" smd rect
			(at -0.889 0 90)
			(size 1.016 1.27)
			(layers "B.Cu" "B.Mask" "B.Paste")
			(net "GND")
		)
	)
	(footprint ""
		(layer "B.Cu")
		(at 372.891304 -398.942052 90)
		(property "Reference" "C1056"
			(at 0 0 90)
			(layer "B.SilkS")
			(hide yes)
			(effects
				(font
					(size 1.27 1.27)
				)
				(justify mirror)
			)
		)
		(property "Value" ""
			(at 0 0 90)
			(layer "B.Fab")
			(effects
				(font
					(size 1.27 1.27)
				)
				(justify mirror)
			)
		)
		(duplicate_pad_numbers_are_jumpers no)
		(fp_line
			(start 0.7874 -0.4064)
			(end -0.7874 -0.4064)
			(stroke
				(width 0.1524)
				(type default)
			)
			(layer "B.SilkS")
		)
		(fp_line
			(start -0.7874 -0.4064)
			(end -0.7874 0.4064)
			(stroke
				(width 0.1524)
				(type default)
			)
			(layer "B.SilkS")
		)
		(fp_line
			(start 0.7874 0.4064)
			(end 0.7874 -0.4064)
			(stroke
				(width 0.1524)
				(type default)
			)
			(layer "B.SilkS")
		)
		(fp_line
			(start -0.7874 0.4064)
			(end 0.7874 0.4064)
			(stroke
				(width 0.1524)
				(type default)
			)
			(layer "B.SilkS")
		)
		(fp_line
			(start 0.67945 -0.305054)
			(end 0.12065 -0.305054)
			(stroke
				(width 0.1)
				(type default)
			)
			(layer "B.Fab")
		)
		(fp_line
			(start 0.12065 -0.305054)
			(end 0.12065 -0.2794)
			(stroke
				(width 0.1)
				(type default)
			)
			(layer "B.Fab")
		)
		(fp_line
			(start -0.12065 -0.3048)
			(end -0.67945 -0.3048)
			(stroke
				(width 0.1)
				(type default)
			)
			(layer "B.Fab")
		)
		(fp_line
			(start -0.67945 -0.3048)
			(end -0.67945 0.3048)
			(stroke
				(width 0.1)
				(type default)
			)
			(layer "B.Fab")
		)
		(fp_line
			(start 0.12065 -0.2794)
			(end -0.12065 -0.2794)
			(stroke
				(width 0.1)
				(type default)
			)
			(layer "B.Fab")
		)
		(fp_line
			(start -0.12065 -0.2794)
			(end -0.12065 -0.3048)
			(stroke
				(width 0.1)
				(type default)
			)
			(layer "B.Fab")
		)
		(fp_line
			(start 0.12065 0.2794)
			(end 0.12065 0.3048)
			(stroke
				(width 0.1)
				(type default)
			)
			(layer "B.Fab")
		)
		(fp_line
			(start -0.120396 0.2794)
			(end 0.12065 0.2794)
			(stroke
				(width 0.1)
				(type default)
			)
			(layer "B.Fab")
		)
		(fp_line
			(start 0.67945 0.3048)
			(end 0.67945 -0.305054)
			(stroke
				(width 0.1)
				(type default)
			)
			(layer "B.Fab")
		)
		(fp_line
			(start 0.12065 0.3048)
			(end 0.67945 0.3048)
			(stroke
				(width 0.1)
				(type default)
			)
			(layer "B.Fab")
		)
		(fp_line
			(start -0.120396 0.3048)
			(end -0.120396 0.2794)
			(stroke
				(width 0.1)
				(type default)
			)
			(layer "B.Fab")
		)
		(fp_line
			(start -0.67945 0.3048)
			(end -0.120396 0.3048)
			(stroke
				(width 0.1)
				(type default)
			)
			(layer "B.Fab")
		)
		(pad "1" smd circle
			(at 0.40005 0 270)
			(size 0 0)
			(layers "B.Cu" "B.Mask" "B.Paste")
			(net "P0V9_CPU0_RT3_2A")
		)
		(pad "2" smd circle
			(at -0.40005 0 270)
			(size 0 0)
			(layers "B.Cu" "B.Mask" "B.Paste")
			(net "GND")
		)
	)
	(footprint ""
		(layer "B.Cu")
		(at 381.645922 -148.30171 -90)
		(property "Reference" "PR441"
			(at 0 0 90)
			(layer "B.SilkS")
			(hide yes)
			(effects
				(font
					(size 1.27 1.27)
				)
				(justify mirror)
			)
		)
		(property "Value" ""
			(at 0 0 90)
			(layer "B.Fab")
			(effects
				(font
					(size 1.27 1.27)
				)
				(justify mirror)
			)
		)
		(duplicate_pad_numbers_are_jumpers no)
		(fp_line
			(start -0.7874 0.4064)
			(end 0.7874 0.4064)
			(stroke
				(width 0.1524)
				(type default)
			)
			(layer "B.SilkS")
		)
		(fp_line
			(start 0.7874 0.4064)
			(end 0.7874 -0.4064)
			(stroke
				(width 0.1524)
				(type default)
			)
			(layer "B.SilkS")
		)
		(fp_line
			(start -0.7874 -0.4064)
			(end -0.7874 0.4064)
			(stroke
				(width 0.1524)
				(type default)
			)
			(layer "B.SilkS")
		)
		(fp_line
			(start 0.7874 -0.4064)
			(end -0.7874 -0.4064)
			(stroke
				(width 0.1524)
				(type default)
			)
			(layer "B.SilkS")
		)
		(fp_line
			(start -0.67945 0.3048)
			(end -0.120396 0.3048)
			(stroke
				(width 0.1)
				(type default)
			)
			(layer "B.Fab")
		)
		(fp_line
			(start -0.120396 0.3048)
			(end -0.120396 0.2794)
			(stroke
				(width 0.1)
				(type default)
			)
			(layer "B.Fab")
		)
		(fp_line
			(start 0.12065 0.3048)
			(end 0.67945 0.3048)
			(stroke
				(width 0.1)
				(type default)
			)
			(layer "B.Fab")
		)
		(fp_line
			(start 0.67945 0.3048)
			(end 0.67945 -0.305054)
			(stroke
				(width 0.1)
				(type default)
			)
			(layer "B.Fab")
		)
		(fp_line
			(start -0.120396 0.2794)
			(end 0.12065 0.2794)
			(stroke
				(width 0.1)
				(type default)
			)
			(layer "B.Fab")
		)
		(fp_line
			(start 0.12065 0.2794)
			(end 0.12065 0.3048)
			(stroke
				(width 0.1)
				(type default)
			)
			(layer "B.Fab")
		)
		(fp_line
			(start -0.12065 -0.2794)
			(end -0.12065 -0.3048)
			(stroke
				(width 0.1)
				(type default)
			)
			(layer "B.Fab")
		)
		(fp_line
			(start 0.12065 -0.2794)
			(end -0.12065 -0.2794)
			(stroke
				(width 0.1)
				(type default)
			)
			(layer "B.Fab")
		)
		(fp_line
			(start -0.67945 -0.3048)
			(end -0.67945 0.3048)
			(stroke
				(width 0.1)
				(type default)
			)
			(layer "B.Fab")
		)
		(fp_line
			(start -0.12065 -0.3048)
			(end -0.67945 -0.3048)
			(stroke
				(width 0.1)
				(type default)
			)
			(layer "B.Fab")
		)
		(fp_line
			(start 0.12065 -0.305054)
			(end 0.12065 -0.2794)
			(stroke
				(width 0.1)
				(type default)
			)
			(layer "B.Fab")
		)
		(fp_line
			(start 0.67945 -0.305054)
			(end 0.12065 -0.305054)
			(stroke
				(width 0.1)
				(type default)
			)
			(layer "B.Fab")
		)
		(pad "1" smd circle
			(at 0.40005 0 90)
			(size 0 0)
			(layers "B.Cu" "B.Mask" "B.Paste")
			(net "NC_PVDDCR_CPU0_P0_IMON9")
		)
		(pad "2" smd circle
			(at -0.40005 0 90)
			(size 0 0)
			(layers "B.Cu" "B.Mask" "B.Paste")
			(net "GND")
		)
	)
	(footprint ""
		(layer "B.Cu")
		(at 343.43467 -328.212704 -90)
		(property "Reference" "PC98"
			(at 9.746996 -0.271526 270)
			(unlocked yes)
			(layer "B.SilkS")
			(effects
				(font
					(size 0.7874 0.5842)
					(thickness 0.1524)
				)
				(justify left mirror)
			)
		)
		(property "Value" ""
			(at 0 0 90)
			(layer "B.Fab")
			(effects
				(font
					(size 1.27 1.27)
				)
				(justify mirror)
			)
		)
		(duplicate_pad_numbers_are_jumpers no)
		(fp_line
			(start -4.533392 2.249932)
			(end 4.533392 2.249932)
			(stroke
				(width 0.1524)
				(type default)
			)
			(layer "B.SilkS")
		)
		(fp_line
			(start 4.533392 2.249932)
			(end 4.533392 -2.249932)
			(stroke
				(width 0.1524)
				(type default)
			)
			(layer "B.SilkS")
		)
		(fp_line
			(start -4.533392 -2.249932)
			(end -4.533392 2.249932)
			(stroke
				(width 0.1524)
				(type default)
			)
			(layer "B.SilkS")
		)
		(fp_line
			(start 4.533392 -2.249932)
			(end -4.533392 -2.249932)
			(stroke
				(width 0.1524)
				(type default)
			)
			(layer "B.SilkS")
		)
		(fp_rect
			(start 5.39242 2.326132)
			(end 4.533392 -2.326132)
			(stroke
				(width 0)
				(type default)
			)
			(fill yes)
			(layer "B.SilkS")
		)
		(fp_line
			(start -3.750056 2.249932)
			(end 3.750056 2.249932)
			(stroke
				(width 0.1)
				(type default)
			)
			(layer "B.Fab")
		)
		(fp_line
			(start 3.750056 2.249932)
			(end 3.750056 -2.249932)
			(stroke
				(width 0.1)
				(type default)
			)
			(layer "B.Fab")
		)
		(fp_line
			(start -3.750056 -2.249932)
			(end -3.750056 2.249932)
			(stroke
				(width 0.1)
				(type default)
			)
			(layer "B.Fab")
		)
		(fp_line
			(start 3.750056 -2.249932)
			(end -3.750056 -2.249932)
			(stroke
				(width 0.1)
				(type default)
			)
			(layer "B.Fab")
		)
		(fp_text user "+"
			(at 6.322314 0.786384 180)
			(unlocked yes)
			(layer "B.SilkS")
			(effects
				(font
					(size 1.905 1.4224)
					(thickness 0.1524)
				)
				(justify left mirror)
			)
		)
		(fp_text user "-"
			(at -4.8514 -0.14605 270)
			(unlocked yes)
			(layer "B.SilkS")
			(effects
				(font
					(size 1.905 1.4224)
					(thickness 0.1524)
				)
				(justify left mirror)
			)
		)
		(fp_text user "+"
			(at 6.322314 0.786384 180)
			(unlocked yes)
			(layer "B.Fab")
			(effects
				(font
					(size 1.905 1.4224)
					(thickness 0.1524)
				)
				(justify left mirror)
			)
		)
		(fp_text user "-"
			(at -4.8514 -0.14605 270)
			(unlocked yes)
			(layer "B.Fab")
			(effects
				(font
					(size 1.905 1.4224)
					(thickness 0.1524)
				)
				(justify left mirror)
			)
		)
		(pad "1" smd rect
			(at 3.199892 0 90)
			(size 2.413 2.8194)
			(layers "B.Cu" "B.Mask" "B.Paste")
			(net "PVDDCR_CPU1_P0")
		)
		(pad "2" smd rect
			(at -3.199892 0 90)
			(size 2.413 2.8194)
			(layers "B.Cu" "B.Mask" "B.Paste")
			(net "GND")
		)
	)
	(footprint ""
		(layer "B.Cu")
		(at 408.597608 -329.987402 90)
		(property "Reference" "R5055"
			(at 0 0 90)
			(layer "B.SilkS")
			(hide yes)
			(effects
				(font
					(size 1.27 1.27)
				)
				(justify mirror)
			)
		)
		(property "Value" ""
			(at 0 0 90)
			(layer "B.Fab")
			(effects
				(font
					(size 1.27 1.27)
				)
				(justify mirror)
			)
		)
		(duplicate_pad_numbers_are_jumpers no)
		(fp_line
			(start 0.7874 -0.4064)
			(end -0.7874 -0.4064)
			(stroke
				(width 0.1524)
				(type default)
			)
			(layer "B.SilkS")
		)
		(fp_line
			(start -0.7874 -0.4064)
			(end -0.7874 0.4064)
			(stroke
				(width 0.1524)
				(type default)
			)
			(layer "B.SilkS")
		)
		(fp_line
			(start 0.7874 0.4064)
			(end 0.7874 -0.4064)
			(stroke
				(width 0.1524)
				(type default)
			)
			(layer "B.SilkS")
		)
		(fp_line
			(start -0.7874 0.4064)
			(end 0.7874 0.4064)
			(stroke
				(width 0.1524)
				(type default)
			)
			(layer "B.SilkS")
		)
		(fp_line
			(start 0.67945 -0.305054)
			(end 0.12065 -0.305054)
			(stroke
				(width 0.1)
				(type default)
			)
			(layer "B.Fab")
		)
		(fp_line
			(start 0.12065 -0.305054)
			(end 0.12065 -0.2794)
			(stroke
				(width 0.1)
				(type default)
			)
			(layer "B.Fab")
		)
		(fp_line
			(start -0.12065 -0.3048)
			(end -0.67945 -0.3048)
			(stroke
				(width 0.1)
				(type default)
			)
			(layer "B.Fab")
		)
		(fp_line
			(start -0.67945 -0.3048)
			(end -0.67945 0.3048)
			(stroke
				(width 0.1)
				(type default)
			)
			(layer "B.Fab")
		)
		(fp_line
			(start 0.12065 -0.2794)
			(end -0.12065 -0.2794)
			(stroke
				(width 0.1)
				(type default)
			)
			(layer "B.Fab")
		)
		(fp_line
			(start -0.12065 -0.2794)
			(end -0.12065 -0.3048)
			(stroke
				(width 0.1)
				(type default)
			)
			(layer "B.Fab")
		)
		(fp_line
			(start 0.12065 0.2794)
			(end 0.12065 0.3048)
			(stroke
				(width 0.1)
				(type default)
			)
			(layer "B.Fab")
		)
		(fp_line
			(start -0.120396 0.2794)
			(end 0.12065 0.2794)
			(stroke
				(width 0.1)
				(type default)
			)
			(layer "B.Fab")
		)
		(fp_line
			(start 0.67945 0.3048)
			(end 0.67945 -0.305054)
			(stroke
				(width 0.1)
				(type default)
			)
			(layer "B.Fab")
		)
		(fp_line
			(start 0.12065 0.3048)
			(end 0.67945 0.3048)
			(stroke
				(width 0.1)
				(type default)
			)
			(layer "B.Fab")
		)
		(fp_line
			(start -0.120396 0.3048)
			(end -0.120396 0.2794)
			(stroke
				(width 0.1)
				(type default)
			)
			(layer "B.Fab")
		)
		(fp_line
			(start -0.67945 0.3048)
			(end -0.120396 0.3048)
			(stroke
				(width 0.1)
				(type default)
			)
			(layer "B.Fab")
		)
		(pad "1" smd circle
			(at 0.40005 0 270)
			(size 0 0)
			(layers "B.Cu" "B.Mask" "B.Paste")
			(net "P1V5_BAT")
		)
		(pad "2" smd circle
			(at -0.40005 0 270)
			(size 0 0)
			(layers "B.Cu" "B.Mask" "B.Paste")
			(net "CPU0_RTC_LDO_SELECT")
		)
	)
)
